(kicad_pcb
	(version 20260206)
	(generator "pcbnew")
	(generator_version "10.0")
	(general
		(thickness 1.6)
		(legacy_teardrops no)
	)
	(paper "A4")
	(title_block
		(title "04192023_DAF0TMB3IC0_F0TG_MB_C_brd_V02_OCP.brd")
		(comment 1 "Grand Teton / footprints 669-672 of 8354")
	)
	(layers
		(0 "F.Cu" signal "TOP")
		(4 "In1.Cu" signal "GND")
		(6 "In2.Cu" signal "IN1")
		(8 "In3.Cu" signal "GND1")
		(10 "In4.Cu" signal "IN2")
		(12 "In5.Cu" signal "GND2")
		(14 "In6.Cu" signal "IN3")
		(16 "In7.Cu" signal "GND3")
		(18 "In8.Cu" signal "VCC")
		(20 "In9.Cu" signal "VCC1")
		(22 "In10.Cu" signal "GND4")
		(24 "In11.Cu" signal "IN4")
		(26 "In12.Cu" signal "GND5")
		(28 "In13.Cu" signal "IN5")
		(30 "In14.Cu" signal "GND6")
		(32 "In15.Cu" signal "IN6")
		(34 "In16.Cu" signal "GND7")
		(2 "B.Cu" signal "BOTTOM")
		(9 "F.Adhes" user "F.Adhesive")
		(11 "B.Adhes" user "B.Adhesive")
		(13 "F.Paste" user "Package Geometry/Pastemask Top")
		(15 "B.Paste" user "Package Geometry/Pastemask Bottom")
		(5 "F.SilkS" user "Ref Des/Silkscreen Top")
		(7 "B.SilkS" user "Ref Des/Silkscreen Bottom")
		(1 "F.Mask" user "Board Geometry/Soldermask Top")
		(3 "B.Mask" user "Board Geometry/Soldermask Bottom")
		(17 "Dwgs.User" user "User.Drawings")
		(19 "Cmts.User" user "User.Comments")
		(21 "Eco1.User" user "User.Eco1")
		(23 "Eco2.User" user "User.Eco2")
		(25 "Edge.Cuts" user "Board Geometry/Outline")
		(27 "Margin" user)
		(31 "F.CrtYd" user "Package Geometry/Place Bound Top")
		(29 "B.CrtYd" user "Package Geometry/Place Bound Bottom")
		(35 "F.Fab" user "Ref Des/Assembly Top")
		(33 "B.Fab" user "Ref Des/Assembly Bottom")
	)
	(footprint ""
		(layer "F.Cu")
		(at 91.776296 -333.29499 90)
		(property "Reference" "PR517"
			(at 0 0 90)
			(layer "F.SilkS")
			(hide yes)
			(effects
				(font
					(size 1.27 1.27)
				)
			)
		)
		(property "Value" ""
			(at 0 0 90)
			(layer "F.Fab")
			(effects
				(font
					(size 1.27 1.27)
				)
			)
		)
		(duplicate_pad_numbers_are_jumpers no)
		(fp_line
			(start 0.7874 -0.4064)
			(end 0.7874 0.4064)
			(stroke
				(width 0.1524)
				(type default)
			)
			(layer "F.SilkS")
		)
		(fp_line
			(start -0.7874 -0.4064)
			(end 0.7874 -0.4064)
			(stroke
				(width 0.1524)
				(type default)
			)
			(layer "F.SilkS")
		)
		(fp_line
			(start 0.7874 0.4064)
			(end -0.7874 0.4064)
			(stroke
				(width 0.1524)
				(type default)
			)
			(layer "F.SilkS")
		)
		(fp_line
			(start -0.7874 0.4064)
			(end -0.7874 -0.4064)
			(stroke
				(width 0.1524)
				(type default)
			)
			(layer "F.SilkS")
		)
		(fp_line
			(start -0.12065 -0.305054)
			(end -0.12065 -0.2794)
			(stroke
				(width 0.1)
				(type default)
			)
			(layer "F.Fab")
		)
		(fp_line
			(start -0.67945 -0.305054)
			(end -0.12065 -0.305054)
			(stroke
				(width 0.1)
				(type default)
			)
			(layer "F.Fab")
		)
		(fp_line
			(start 0.67945 -0.3048)
			(end 0.67945 0.3048)
			(stroke
				(width 0.1)
				(type default)
			)
			(layer "F.Fab")
		)
		(fp_line
			(start 0.12065 -0.3048)
			(end 0.67945 -0.3048)
			(stroke
				(width 0.1)
				(type default)
			)
			(layer "F.Fab")
		)
		(fp_line
			(start 0.12065 -0.2794)
			(end 0.12065 -0.3048)
			(stroke
				(width 0.1)
				(type default)
			)
			(layer "F.Fab")
		)
		(fp_line
			(start -0.12065 -0.2794)
			(end 0.12065 -0.2794)
			(stroke
				(width 0.1)
				(type default)
			)
			(layer "F.Fab")
		)
		(fp_line
			(start 0.120396 0.2794)
			(end -0.12065 0.2794)
			(stroke
				(width 0.1)
				(type default)
			)
			(layer "F.Fab")
		)
		(fp_line
			(start -0.12065 0.2794)
			(end -0.12065 0.3048)
			(stroke
				(width 0.1)
				(type default)
			)
			(layer "F.Fab")
		)
		(fp_line
			(start 0.67945 0.3048)
			(end 0.120396 0.3048)
			(stroke
				(width 0.1)
				(type default)
			)
			(layer "F.Fab")
		)
		(fp_line
			(start 0.120396 0.3048)
			(end 0.120396 0.2794)
			(stroke
				(width 0.1)
				(type default)
			)
			(layer "F.Fab")
		)
		(fp_line
			(start -0.12065 0.3048)
			(end -0.67945 0.3048)
			(stroke
				(width 0.1)
				(type default)
			)
			(layer "F.Fab")
		)
		(fp_line
			(start -0.67945 0.3048)
			(end -0.67945 -0.305054)
			(stroke
				(width 0.1)
				(type default)
			)
			(layer "F.Fab")
		)
		(pad "1" smd circle
			(at -0.40005 0 90)
			(size 0 0)
			(layers "F.Cu" "F.Mask" "F.Paste")
			(net "SW_PVDDCR_CPU1_P1_SW5_RC")
		)
		(pad "2" smd circle
			(at 0.40005 0 90)
			(size 0 0)
			(layers "F.Cu" "F.Mask" "F.Paste")
			(net "GND")
		)
	)
	(footprint ""
		(layer "F.Cu")
		(at 97.745296 -412.931102 90)
		(property "Reference" "R4181"
			(at 0 0 90)
			(layer "F.SilkS")
			(hide yes)
			(effects
				(font
					(size 1.27 1.27)
				)
			)
		)
		(property "Value" ""
			(at 0 0 90)
			(layer "F.Fab")
			(effects
				(font
					(size 1.27 1.27)
				)
			)
		)
		(duplicate_pad_numbers_are_jumpers no)
		(fp_line
			(start 0.7874 -0.4064)
			(end 0.7874 0.4064)
			(stroke
				(width 0.1524)
				(type default)
			)
			(layer "F.SilkS")
		)
		(fp_line
			(start -0.7874 -0.4064)
			(end 0.7874 -0.4064)
			(stroke
				(width 0.1524)
				(type default)
			)
			(layer "F.SilkS")
		)
		(fp_line
			(start 0.7874 0.4064)
			(end -0.7874 0.4064)
			(stroke
				(width 0.1524)
				(type default)
			)
			(layer "F.SilkS")
		)
		(fp_line
			(start -0.7874 0.4064)
			(end -0.7874 -0.4064)
			(stroke
				(width 0.1524)
				(type default)
			)
			(layer "F.SilkS")
		)
		(fp_line
			(start -0.12065 -0.305054)
			(end -0.12065 -0.2794)
			(stroke
				(width 0.1)
				(type default)
			)
			(layer "F.Fab")
		)
		(fp_line
			(start -0.67945 -0.305054)
			(end -0.12065 -0.305054)
			(stroke
				(width 0.1)
				(type default)
			)
			(layer "F.Fab")
		)
		(fp_line
			(start 0.67945 -0.3048)
			(end 0.67945 0.3048)
			(stroke
				(width 0.1)
				(type default)
			)
			(layer "F.Fab")
		)
		(fp_line
			(start 0.12065 -0.3048)
			(end 0.67945 -0.3048)
			(stroke
				(width 0.1)
				(type default)
			)
			(layer "F.Fab")
		)
		(fp_line
			(start 0.12065 -0.2794)
			(end 0.12065 -0.3048)
			(stroke
				(width 0.1)
				(type default)
			)
			(layer "F.Fab")
		)
		(fp_line
			(start -0.12065 -0.2794)
			(end 0.12065 -0.2794)
			(stroke
				(width 0.1)
				(type default)
			)
			(layer "F.Fab")
		)
		(fp_line
			(start 0.120396 0.2794)
			(end -0.12065 0.2794)
			(stroke
				(width 0.1)
				(type default)
			)
			(layer "F.Fab")
		)
		(fp_line
			(start -0.12065 0.2794)
			(end -0.12065 0.3048)
			(stroke
				(width 0.1)
				(type default)
			)
			(layer "F.Fab")
		)
		(fp_line
			(start 0.67945 0.3048)
			(end 0.120396 0.3048)
			(stroke
				(width 0.1)
				(type default)
			)
			(layer "F.Fab")
		)
		(fp_line
			(start 0.120396 0.3048)
			(end 0.120396 0.2794)
			(stroke
				(width 0.1)
				(type default)
			)
			(layer "F.Fab")
		)
		(fp_line
			(start -0.12065 0.3048)
			(end -0.67945 0.3048)
			(stroke
				(width 0.1)
				(type default)
			)
			(layer "F.Fab")
		)
		(fp_line
			(start -0.67945 0.3048)
			(end -0.67945 -0.305054)
			(stroke
				(width 0.1)
				(type default)
			)
			(layer "F.Fab")
		)
		(pad "1" smd circle
			(at -0.40005 0 90)
			(size 0 0)
			(layers "F.Cu" "F.Mask" "F.Paste")
			(net "SMB_LM75_2_3V3AUX_SDA")
		)
		(pad "2" smd circle
			(at 0.40005 0 90)
			(size 0 0)
			(layers "F.Cu" "F.Mask" "F.Paste")
			(net "SMB_LM75_2_3V3AUX_SDA_R1")
		)
	)
	(footprint ""
		(layer "F.Cu")
		(at 351.666048 -339.93455)
		(property "Reference" "PU11"
			(at -1.527048 -8.01878 0)
			(unlocked yes)
			(layer "F.SilkS")
			(effects
				(font
					(size 0.7874 0.5842)
					(thickness 0.1524)
				)
				(justify left)
			)
		)
		(property "Value" ""
			(at 0 0 0)
			(layer "F.Fab")
			(effects
				(font
					(size 1.27 1.27)
				)
			)
		)
		(duplicate_pad_numbers_are_jumpers no)
		(fp_line
			(start -2.500122 -2.999994)
			(end -2.24409 -2.999994)
			(stroke
				(width 0.1524)
				(type default)
			)
			(layer "F.SilkS")
		)
		(fp_line
			(start -2.500122 -2.529078)
			(end -2.500122 -2.999994)
			(stroke
				(width 0.1524)
				(type default)
			)
			(layer "F.SilkS")
		)
		(fp_line
			(start -2.500122 0.6604)
			(end -2.500122 0.229108)
			(stroke
				(width 0.1524)
				(type default)
			)
			(layer "F.SilkS")
		)
		(fp_line
			(start -2.500122 2.999994)
			(end -2.500122 2.339594)
			(stroke
				(width 0.1524)
				(type default)
			)
			(layer "F.SilkS")
		)
		(fp_line
			(start -2.2987 2.999994)
			(end -2.500122 2.999994)
			(stroke
				(width 0.1524)
				(type default)
			)
			(layer "F.SilkS")
		)
		(fp_line
			(start 2.31394 -2.999994)
			(end 2.500122 -2.999994)
			(stroke
				(width 0.1524)
				(type default)
			)
			(layer "F.SilkS")
		)
		(fp_line
			(start 2.500122 -2.999994)
			(end 2.500122 -2.44348)
			(stroke
				(width 0.1524)
				(type default)
			)
			(layer "F.SilkS")
		)
		(fp_line
			(start 2.500122 2.339594)
			(end 2.500122 2.999994)
			(stroke
				(width 0.1524)
				(type default)
			)
			(layer "F.SilkS")
		)
		(fp_line
			(start 2.500122 2.999994)
			(end 2.2987 2.999994)
			(stroke
				(width 0.1524)
				(type default)
			)
			(layer "F.SilkS")
		)
		(fp_poly
			(pts
				(xy -2.765298 -2.448814) (xy -3.438906 -2.67335) (xy -2.989834 -3.122422)
			)
			(stroke
				(width 0)
				(type default)
			)
			(fill yes)
			(layer "F.SilkS")
		)
		(fp_line
			(start -2.500122 -2.999994)
			(end 2.500122 -2.999994)
			(stroke
				(width 0.1)
				(type default)
			)
			(layer "F.Fab")
		)
		(fp_line
			(start -2.500122 2.999994)
			(end -2.500122 -2.999994)
			(stroke
				(width 0.1)
				(type default)
			)
			(layer "F.Fab")
		)
		(fp_line
			(start 2.500122 -2.999994)
			(end 2.500122 2.999994)
			(stroke
				(width 0.1)
				(type default)
			)
			(layer "F.Fab")
		)
		(fp_line
			(start 2.500122 2.999994)
			(end -2.500122 2.999994)
			(stroke
				(width 0.1)
				(type default)
			)
			(layer "F.Fab")
		)
		(fp_poly
			(pts
				(xy -4.218432 -2.783078) (xy -4.218432 -1.767078) (xy -3.202432 -2.275078)
			)
			(stroke
				(width 0)
				(type default)
			)
			(fill yes)
			(layer "F.Fab")
		)
		(pad "1" smd rect
			(at -2.400046 -2.275078 90)
			(size 0.2286 0.6096)
			(layers "F.Cu" "F.Mask" "F.Paste")
			(net "PVDDCR_CPU1_P0_VOS6")
		)
		(pad "2" smd rect
			(at -2.400046 -1.82499 90)
			(size 0.2286 0.6096)
			(layers "F.Cu" "F.Mask" "F.Paste")
			(net "GND")
		)
		(pad "3" smd rect
			(at -2.400046 -1.374902 90)
			(size 0.2286 0.6096)
			(layers "F.Cu" "F.Mask" "F.Paste")
			(net "PVDDCR_CPU1_P0_VCC6")
		)
		(pad "4" smd rect
			(at -2.400046 -0.925068 90)
			(size 0.2286 0.6096)
			(layers "F.Cu" "F.Mask" "F.Paste")
			(net "PVDDCR_CPU1_P0_PVCC")
		)
		(pad "5" smd rect
			(at -2.400046 -0.47498 90)
			(size 0.2286 0.6096)
			(layers "F.Cu" "F.Mask" "F.Paste")
			(net "GND")
		)
		(pad "6" smd rect
			(at -2.400046 -0.024892 90)
			(size 0.2286 0.6096)
			(layers "F.Cu" "F.Mask" "F.Paste")
			(net "NC_PVDDCR_CPU1_P0_GL1_6")
		)
		(pad "7_9-20_24" smd circle
			(at 0 1.150112 90)
			(size 0 0)
			(layers "F.Cu" "F.Mask" "F.Paste")
			(net "GND")
		)
		(pad "10_19" smd rect
			(at 0 2.899918 90)
			(size 0.6096 4.318)
			(layers "F.Cu" "F.Mask" "F.Paste")
			(net "SW_PVDDCR_CPU1_P0_SW6")
		)
		(pad "25_29" smd rect
			(at 1.549908 -1.279906 270)
			(size 2.0574 2.3114)
			(layers "F.Cu" "F.Mask" "F.Paste")
			(net "SW_P12V_AUX_PVDDCR_CPU1_P0_FLT")
		)
		(pad "30" smd rect
			(at 2.05994 -2.899918)
			(size 0.2286 0.6096)
			(layers "F.Cu" "F.Mask" "F.Paste")
			(net "SW_P12V_AUX_PVDDCR_CPU1_P0_FLT")
		)
		(pad "31" smd rect
			(at 1.610106 -2.899918)
			(size 0.2286 0.6096)
			(layers "F.Cu" "F.Mask" "F.Paste")
			(net "NC_PVDDCR_CPU1_P0_DNC6")
		)
		(pad "32" smd rect
			(at 1.160018 -2.899918)
			(size 0.2286 0.6096)
			(layers "F.Cu" "F.Mask" "F.Paste")
			(net "SW_PVDDCR_CPU1_P0_BOOTR6")
		)
		(pad "33" smd rect
			(at 0.70993 -2.899918)
			(size 0.2286 0.6096)
			(layers "F.Cu" "F.Mask" "F.Paste")
			(net "SW_PVDDCR_CPU1_P0_BOOT6")
		)
		(pad "34" smd rect
			(at 0.260096 -2.899918)
			(size 0.2286 0.6096)
			(layers "F.Cu" "F.Mask" "F.Paste")
			(net "PVDDCR_CPU1_P0_PWM6")
		)
		(pad "35" smd rect
			(at -0.189992 -2.899918)
			(size 0.2286 0.6096)
			(layers "F.Cu" "F.Mask" "F.Paste")
			(net "PVDDCR_CPU1_P0_VCC6")
		)
		(pad "36" smd rect
			(at -0.64008 -2.899918)
			(size 0.2286 0.6096)
			(layers "F.Cu" "F.Mask" "F.Paste")
			(net "PVDDCR_CPU1_P0_TEMP0")
		)
		(pad "37" smd rect
			(at -1.089914 -2.899918)
			(size 0.2286 0.6096)
			(layers "F.Cu" "F.Mask" "F.Paste")
			(net "PVDDCR_CPU1_P0_LSET6")
		)
		(pad "38" smd rect
			(at -1.540002 -2.899918)
			(size 0.2286 0.6096)
			(layers "F.Cu" "F.Mask" "F.Paste")
			(net "PVDDCR_CPU1_P0_IMON6")
		)
		(pad "39" smd rect
			(at -1.99009 -2.899918)
			(size 0.2286 0.6096)
			(layers "F.Cu" "F.Mask" "F.Paste")
			(net "PVDDCR_CPU1_P0_VCCS")
		)
		(pad "40" smd rect
			(at -0.87503 -1.27508)
			(size 1.7526 1.9558)
			(layers "F.Cu" "F.Mask" "F.Paste")
			(net "GND")
		)
		(pad "41" smd rect
			(at -1.525016 0.249936 270)
			(size 0.3048 0.4572)
			(layers "F.Cu" "F.Mask" "F.Paste")
			(net "NC_PVDDCR_CPU1_P0_GL2_6")
		)
		(zone
			(layer "F.Cu")
			(hatch none 0.5)
			(connect_pads
				(clearance 0)
			)
			(min_thickness 0.25)
			(keepout
				(tracks not_allowed)
				(vias allowed)
				(pads allowed)
				(copperpour not_allowed)
				(footprints allowed)
			)
			(placement
				(enabled no)
				(sheetname "")
			)
			(fill
				(thermal_gap 0.5)
				(thermal_bridge_width 0.5)
				(island_removal_mode 0)
			)
			(polygon
				(pts
					(xy 349.165926 -337.354164) (xy 349.165926 -337.683856) (xy 354.16617 -337.683856) (xy 354.16617 -337.357212)
					(xy 353.875848 -337.357212) (xy 353.875848 -337.390232) (xy 349.456248 -337.390232) (xy 349.456248 -337.354164)
				)
			)
		)
		(zone
			(layer "F.Cu")
			(hatch none 0.5)
			(connect_pads
				(clearance 0)
			)
			(min_thickness 0.25)
			(keepout
				(tracks not_allowed)
				(vias allowed)
				(pads allowed)
				(copperpour not_allowed)
				(footprints allowed)
			)
			(placement
				(enabled no)
				(sheetname "")
			)
			(fill
				(thermal_gap 0.5)
				(thermal_bridge_width 0.5)
				(island_removal_mode 0)
			)
			(polygon
				(pts
					(xy 351.718118 -340.2203) (xy 351.718118 -342.23833) (xy 349.863918 -342.23833) (xy 349.863918 -341.997284)
					(xy 349.621602 -341.997284) (xy 349.621602 -342.478868) (xy 353.40671 -342.478868) (xy 353.40671 -342.293956)
					(xy 352.009456 -342.293956) (xy 352.009456 -340.134956) (xy 354.16617 -340.134956) (xy 354.16617 -339.885274)
					(xy 352.053144 -339.885274)
				)
			)
		)
	)
	(footprint ""
		(layer "F.Cu")
		(at 36.919662 -427.377098)
		(property "Reference" "C1864"
			(at 0 0 0)
			(layer "F.SilkS")
			(hide yes)
			(effects
				(font
					(size 1.27 1.27)
				)
			)
		)
		(property "Value" ""
			(at 0 0 0)
			(layer "F.Fab")
			(effects
				(font
					(size 1.27 1.27)
				)
			)
		)
		(duplicate_pad_numbers_are_jumpers no)
		(fp_line
			(start -0.7874 -0.4064)
			(end 0.7874 -0.4064)
			(stroke
				(width 0.1524)
				(type default)
			)
			(layer "F.SilkS")
		)
		(fp_line
			(start -0.7874 0.4064)
			(end -0.7874 -0.4064)
			(stroke
				(width 0.1524)
				(type default)
			)
			(layer "F.SilkS")
		)
		(fp_line
			(start 0.7874 -0.4064)
			(end 0.7874 0.4064)
			(stroke
				(width 0.1524)
				(type default)
			)
			(layer "F.SilkS")
		)
		(fp_line
			(start 0.7874 0.4064)
			(end -0.7874 0.4064)
			(stroke
				(width 0.1524)
				(type default)
			)
			(layer "F.SilkS")
		)
		(fp_line
			(start -0.67945 -0.305054)
			(end -0.12065 -0.305054)
			(stroke
				(width 0.1)
				(type default)
			)
			(layer "F.Fab")
		)
		(fp_line
			(start -0.67945 0.3048)
			(end -0.67945 -0.305054)
			(stroke
				(width 0.1)
				(type default)
			)
			(layer "F.Fab")
		)
		(fp_line
			(start -0.12065 -0.305054)
			(end -0.12065 -0.2794)
			(stroke
				(width 0.1)
				(type default)
			)
			(layer "F.Fab")
		)
		(fp_line
			(start -0.12065 -0.2794)
			(end 0.12065 -0.2794)
			(stroke
				(width 0.1)
				(type default)
			)
			(layer "F.Fab")
		)
		(fp_line
			(start -0.12065 0.2794)
			(end -0.12065 0.3048)
			(stroke
				(width 0.1)
				(type default)
			)
			(layer "F.Fab")
		)
		(fp_line
			(start -0.12065 0.3048)
			(end -0.67945 0.3048)
			(stroke
				(width 0.1)
				(type default)
			)
			(layer "F.Fab")
		)
		(fp_line
			(start 0.120396 0.2794)
			(end -0.12065 0.2794)
			(stroke
				(width 0.1)
				(type default)
			)
			(layer "F.Fab")
		)
		(fp_line
			(start 0.120396 0.3048)
			(end 0.120396 0.2794)
			(stroke
				(width 0.1)
				(type default)
			)
			(layer "F.Fab")
		)
		(fp_line
			(start 0.12065 -0.3048)
			(end 0.67945 -0.3048)
			(stroke
				(width 0.1)
				(type default)
			)
			(layer "F.Fab")
		)
		(fp_line
			(start 0.12065 -0.2794)
			(end 0.12065 -0.3048)
			(stroke
				(width 0.1)
				(type default)
			)
			(layer "F.Fab")
		)
		(fp_line
			(start 0.67945 -0.3048)
			(end 0.67945 0.3048)
			(stroke
				(width 0.1)
				(type default)
			)
			(layer "F.Fab")
		)
		(fp_line
			(start 0.67945 0.3048)
			(end 0.120396 0.3048)
			(stroke
				(width 0.1)
				(type default)
			)
			(layer "F.Fab")
		)
		(pad "1" smd circle
			(at -0.40005 0)
			(size 0 0)
			(layers "F.Cu" "F.Mask" "F.Paste")
			(net "P3V3_AUX")
		)
		(pad "2" smd circle
			(at 0.40005 0)
			(size 0 0)
			(layers "F.Cu" "F.Mask" "F.Paste")
			(net "GND")
		)
	)
)
